FILE_TYPE = MACRO_DRAWING;
SET COLOR_WIRE YELLOW;
SET COLOR_PROP ORANGE;
SET COLOR_DOT WHITE;
SET COLOR_ARC YELLOW;
SET COLOR_BODY GREEN;
SET COLOR_NOTE PURPLE;
SET PROP_DISPLAY VALUE;
SET PAGE_NUMBER P18;
FORCEADD SOCKET4677_AZIF0045P001C01CS..6
(1750 2600);
FORCEPROP 1 LAST PART_NUMBER DGA^7000023
J 0
(700 3100);
DISPLAY 0.723404 (700 3100);
PAINT GREEN (700 3100);
DISPLAY INVISIBLE (700 3100);
FORCEPROP 2 LAST PART_TYPE SMLF
J 0
(700 3275);
DISPLAY 1.021277 (700 3275);
FORCEPROP 1 LAST MATERIAL IO
J 0
(700 3025);
DISPLAY 0.723404 (700 3025);
PAINT GREEN (700 3025);
FORCEPROP 2 LAST VALUE SOCKET4677_AZIF0045-P001C01CS
J 0
(700 3225);
DISPLAY 1.021277 (700 3225);
FORCEPROP 1 LAST $LOCATION U2
J 0
(700 3175);
DISPLAY 0.723404 (700 3175);
PAINT GREEN (700 3175);
FORCEPROP 0 LASTPIN (550 2800) $PN AU52
J 2
(540 2810);
DISPLAY 0.680851 (540 2810);
PAINT MONO (540 2810);
FORCEPROP 0 LASTPIN (550 2350) $PN BD77
J 2
(540 2360);
DISPLAY 0.680851 (540 2360);
PAINT MONO (540 2360);
FORCEPROP 0 LASTPIN (550 2450) $PN CD69
J 2
(540 2460);
DISPLAY 0.680851 (540 2460);
PAINT MONO (540 2460);
FORCEPROP 0 LASTPIN (550 2500) $PN CG60
J 2
(540 2510);
DISPLAY 0.680851 (540 2510);
PAINT MONO (540 2510);
FORCEPROP 0 LASTPIN (550 2550) $PN CH61
J 2
(540 2560);
DISPLAY 0.680851 (540 2560);
PAINT MONO (540 2560);
FORCEPROP 0 LASTPIN (550 2600) $PN CK61
J 2
(540 2610);
DISPLAY 0.680851 (540 2610);
PAINT MONO (540 2610);
FORCEPROP 0 LASTPIN (550 2650) $PN CL60
J 2
(540 2660);
DISPLAY 0.680851 (540 2660);
PAINT MONO (540 2660);
FORCEPROP 0 LASTPIN (550 2400) $PN CL70
J 2
(540 2410);
DISPLAY 0.680851 (540 2410);
PAINT MONO (540 2410);
FORCEPROP 0 LASTPIN (550 2700) $PN CW43
J 2
(540 2710);
DISPLAY 0.680851 (540 2710);
PAINT MONO (540 2710);
FORCEPROP 0 LASTPIN (550 2850) $PN DA70
J 2
(540 2860);
DISPLAY 0.680851 (540 2860);
PAINT MONO (540 2860);
FORCEPROP 0 LASTPIN (550 2750) $PN J13
J 2
(540 2760);
DISPLAY 0.680851 (540 2760);
PAINT MONO (540 2760);
FORCEPROP 2 LAST CDS_LIB pure_quanta
J 0
(1750 2600);
DISPLAY INVISIBLE (1750 2600);
FORCEPROP 1 LAST NEEDS_NO_SIZE TRUE
J 0
(1750 2600);
DISPLAY 0.723404 (1750 2600);
PAINT GREEN (1750 2600);
DISPLAY INVISIBLE (1750 2600);
FORCEPROP 1 LAST CDS_LMAN_SYM_OUTLINE -1050,400,1050,-400
J 0
(1750 2600);
DISPLAY 0.468085 (1750 2600);
PAINT GREEN (1750 2600);
DISPLAY INVISIBLE (1750 2600);
FORCEPROP 2 LAST CDS_LOCATION U2
J 0
(700 3325);
DISPLAY 1.021277 (700 3325);
DISPLAY INVISIBLE (700 3325);
FORCEPROP 0 LAST $SEC 6
J 0
(700 3325);
DISPLAY 0.680851 (700 3325);
PAINT MONO (700 3325);
DISPLAY INVISIBLE (700 3325);
FORCEPROP 2 LAST CDS_SEC 6
J 0
(700 3325);
DISPLAY 1.021277 (700 3325);
DISPLAY INVISIBLE (700 3325);
FORCEPROP 1 LAST PATH I1
J 0
(1750 2600);
DISPLAY 0.723404 (1750 2600);
PAINT GREEN (1750 2600);
DISPLAY INVISIBLE (1750 2600);
FORCEADD QUANTA_TITLE_BLOCK_C..1
(6225 -1625);
FORCEPROP 0 LAST CDS_CON_LAST_MODIFIED Fri Aug 25 14:00:04 2023
J 0
(4340 -1610);
PAINT MONO (4340 -1610);
DISPLAY INVISIBLE (4340 -1610);
FORCEPROP 2 LAST CUSTOM_TXT_CDS <XR_PAGE_TITLE>
J 0
(-1665 3625);
DISPLAY 0.638298 (-1665 3625);
PAINT PINK (-1665 3625);
DISPLAY INVISIBLE (-1665 3625);
FORCEPROP 2 LAST CUSTOM_TXT_CDS <CON_PAGE_NUM> OF <CON_TOTAL_PAGES>
J 0
(5779 -1607);
DISPLAY 0.978723 (5779 -1607);
FORCEPROP 2 LAST CUSTOM_TXT_CDS <Q_NUMBER>
J 0
(4822 -1522);
DISPLAY 1.212766 (4822 -1522);
FORCEPROP 2 LAST CUSTOM_TXT_CDS <CON_LAST_MODIFIED>
J 0
(4340 -1610);
DISPLAY 0.978723 (4340 -1610);
FORCEPROP 2 LAST CUSTOM_TXT_CDS <Q_REV>
J 0
(6041 -1522);
DISPLAY 1.212766 (6041 -1522);
FORCEPROP 2 LAST CUSTOM_TXT_CDS <Q_PROJ>
J 0
(3843 -1523);
DISPLAY 1.212766 (3843 -1523);
FORCEPROP 1 LAST CUSTOM_TXT_CDS <NAME_2>
J 0
(3050 -1575);
FORCEPROP 1 LAST CUSTOM_TXT_CDS <NAME_1>
J 0
(3050 -1450);
FORCEPROP 1 LAST Q_TITLE SPR CPU0 MISC:SPARE(6 OF 30)
J 0
(-3141 -1599);
DISPLAY 1.957447 (-3141 -1599);
PAINT GREEN (-3141 -1599);
FORCEPROP 1 LAST Q_DEPT 
J 1
(2462 -1576);
DISPLAY 1.957447 (2462 -1576);
PAINT GREEN (2462 -1576);
FORCEPROP 2 LAST CDS_LIB pure_quanta
J 0
(6225 -1625);
PAINT MONO (6225 -1625);
DISPLAY INVISIBLE (6225 -1625);
FORCEPROP 1 LAST CDS_LMAN_SYM_OUTLINE -9475,6775,100,-125
J 0
(6225 -1625);
DISPLAY 0.468085 (6225 -1625);
PAINT GREEN (6225 -1625);
DISPLAY INVISIBLE (6225 -1625);
FORCEPROP 2 LAST PAGE_BORDER TRUE
J 0
(-1665 3625);
DISPLAY 0.638298 (-1665 3625);
PAINT PINK (-1665 3625);
DISPLAY INVISIBLE (-1665 3625);
FORCEPROP 2 LAST CDS_XR_PAGE_TITLE CR-18 : @S9S_MB_2U_LIB.S9S_MB_2U(SCH_1):PAGE18
J 0
(-1665 3625);
DISPLAY 0.638298 (-1665 3625);
PAINT PINK (-1665 3625);
DISPLAY INVISIBLE (-1665 3625);
FORCEPROP 1 LAST COMMENT_BODY TRUE
J 0
(6237 -1638);
DISPLAY 0.978723 (6237 -1638);
PAINT GREEN (6237 -1638);
DISPLAY INVISIBLE (6237 -1638);
WIRE 16 -1 (550 2850)(-1150 2850);
FORCEPROP 2 LAST SIG_NAME TP_CPU0_SPARE4
J 0
(-1087 2859);
DISPLAY 0.680851 (-1087 2859);
PAINT WHITE (-1087 2859);
WIRE 16 -1 (-1150 2750)(550 2750);
FORCEPROP 2 LAST SIG_NAME TP_CPU0_PPD
J 0
(-1087 2759);
DISPLAY 0.680851 (-1087 2759);
PAINT WHITE (-1087 2759);
WIRE 16 -1 (550 2700)(-1150 2700);
FORCEPROP 2 LAST SIG_NAME TP_CPU0_SPARE6
J 0
(-1087 2709);
DISPLAY 0.680851 (-1087 2709);
PAINT WHITE (-1087 2709);
WIRE 16 -1 (-1150 2500)(550 2500);
FORCEPROP 2 LAST SIG_NAME TP_CPU0_SPARE10
J 0
(-1087 2509);
DISPLAY 0.680851 (-1087 2509);
PAINT WHITE (-1087 2509);
WIRE 16 -1 (-1150 2600)(550 2600);
FORCEPROP 2 LAST SIG_NAME TP_CPU0_SPARE8
J 0
(-1087 2609);
DISPLAY 0.680851 (-1087 2609);
PAINT WHITE (-1087 2609);
WIRE 16 -1 (-1150 2450)(550 2450);
FORCEPROP 2 LAST SIG_NAME TP_CPU0_SPARE11
J 0
(-1087 2459);
DISPLAY 0.680851 (-1087 2459);
PAINT WHITE (-1087 2459);
WIRE 16 -1 (-1150 2800)(550 2800);
FORCEPROP 2 LAST SIG_NAME TP_CPU0_SPARE5
J 0
(-1087 2809);
DISPLAY 0.680851 (-1087 2809);
PAINT WHITE (-1087 2809);
WIRE 16 -1 (550 2550)(-1150 2550);
FORCEPROP 2 LAST SIG_NAME TP_CPU0_SPARE9
J 0
(-1087 2559);
DISPLAY 0.680851 (-1087 2559);
PAINT WHITE (-1087 2559);
WIRE 16 -1 (-1150 2350)(550 2350);
FORCEPROP 2 LAST SIG_NAME TP_CPU0_SPARE13
J 0
(-1087 2359);
DISPLAY 0.680851 (-1087 2359);
PAINT WHITE (-1087 2359);
WIRE 16 -1 (-1150 2650)(550 2650);
FORCEPROP 2 LAST SIG_NAME TP_CPU0_SPARE7
J 0
(-1087 2659);
DISPLAY 0.680851 (-1087 2659);
PAINT WHITE (-1087 2659);
WIRE 16 -1 (550 2400)(-1150 2400);
FORCEPROP 2 LAST SIG_NAME TP_CPU0_SPARE12
J 0
(-1087 2409);
DISPLAY 0.680851 (-1087 2409);
PAINT WHITE (-1087 2409);
QUIT
